# BASEBOARD_FAB2 (Tioga Pass) — schematic netlist excerpt (pin names and nets, part order shuffled) for the footprints in the layout excerpt that follows; sources: Cadence DE-HDL packaged netlist, KiCad conversion of Wiwynn_Tioga_Pass_MB.brd

R9P4  RES  2.7K 1% CHIP  pkg 0402  page 200 : A = P3V3_STBY ; B = IRQ_UV_DETECT_N
C9N12  CAP  0.22UF 16V 10% X7R  pkg 0402  page 182 : A = P3E_CPU1_PE3_MP_C_TXP<9> ; B = P3E_CPU1_PE3_MP_TXP<9>
C9M1  CAP_A  0.01UF 25V 10% X7R  pkg 0402V  page 84 : A = M_K_VREF ; B = GND

(kicad_pcb
	(version 20260206)
	(generator "pcbnew")
	(generator_version "10.0")
	(general
		(thickness 1.6)
		(legacy_teardrops no)
	)
	(paper "A4")
	(title_block
		(title "Wiwynn_Tioga_Pass_MB.brd")
		(comment 1 "Tioga Pass / footprints 2819-2821 of 4770")
	)
	(layers
		(0 "F.Cu" signal "TOP")
		(4 "In1.Cu" signal "L2GND")
		(6 "In2.Cu" signal "L3")
		(8 "In3.Cu" signal "L4GND")
		(10 "In4.Cu" signal "L5")
		(12 "In5.Cu" signal "L6GND")
		(14 "In6.Cu" signal "L7VCC")
		(16 "In7.Cu" signal "L8VCC")
		(18 "In8.Cu" signal "L9GND")
		(20 "In9.Cu" signal "L10")
		(22 "In10.Cu" signal "L11GND")
		(24 "In11.Cu" signal "L12")
		(26 "In12.Cu" signal "L13GND")
		(2 "B.Cu" signal "BOTTOM")
		(9 "F.Adhes" user "F.Adhesive")
		(11 "B.Adhes" user "B.Adhesive")
		(13 "F.Paste" user "Package Geometry/Pastemask Top")
		(15 "B.Paste" user "Package Geometry/Pastemask Bottom")
		(5 "F.SilkS" user "Ref Des/Silkscreen Top")
		(7 "B.SilkS" user "Ref Des/Silkscreen Bottom")
		(1 "F.Mask" user "Board Geometry/Soldermask Top")
		(3 "B.Mask" user "Board Geometry/Soldermask Bottom")
		(17 "Dwgs.User" user "User.Drawings")
		(19 "Cmts.User" user "User.Comments")
		(21 "Eco1.User" user "User.Eco1")
		(23 "Eco2.User" user "User.Eco2")
		(25 "Edge.Cuts" user "Board Geometry/Outline")
		(27 "Margin" user)
		(31 "F.CrtYd" user "Package Geometry/Place Bound Top")
		(29 "B.CrtYd" user "Package Geometry/Place Bound Bottom")
		(35 "F.Fab" user "Ref Des/Assembly Top")
		(33 "B.Fab" user "Ref Des/Assembly Bottom")
	)
	(footprint ""
		(layer "B.Cu")
		(at 16.4084 -87.1601 -90)
		(property "Reference" "R9P4"
			(at 0 0 90)
			(layer "B.SilkS")
			(hide yes)
			(effects
				(font
					(size 1.27 1.27)
				)
				(justify mirror)
			)
		)
		(property "Value" ""
			(at 0 0 90)
			(layer "B.Fab")
			(effects
				(font
					(size 1.27 1.27)
				)
				(justify mirror)
			)
		)
		(duplicate_pad_numbers_are_jumpers no)
		(fp_poly
			(pts
				(xy 0.2794 -0.1016) (xy -0.2794 -0.1016) (xy -0.2794 0.9906) (xy 0.2794 0.9906)
			)
			(stroke
				(width 0)
				(type default)
			)
			(fill no)
			(layer "B.CrtYd")
		)
		(fp_line
			(start -0.2794 0.9906)
			(end -0.2794 -0.1016)
			(stroke
				(width 0.1)
				(type default)
			)
			(layer "B.Fab")
		)
		(fp_line
			(start 0.2794 0.9906)
			(end -0.2794 0.9906)
			(stroke
				(width 0.1)
				(type default)
			)
			(layer "B.Fab")
		)
		(fp_line
			(start -0.2794 -0.1016)
			(end 0.2794 -0.1016)
			(stroke
				(width 0.1)
				(type default)
			)
			(layer "B.Fab")
		)
		(fp_line
			(start 0.2794 -0.1016)
			(end 0.2794 0.9906)
			(stroke
				(width 0.1)
				(type default)
			)
			(layer "B.Fab")
		)
		(pad "1" smd rect
			(at 0 0 90)
			(size 0.508 0.508)
			(layers "B.Cu" "B.Mask" "B.Paste")
			(net "P3V3_STBY")
		)
		(pad "2" smd rect
			(at 0 0.889 90)
			(size 0.508 0.508)
			(layers "B.Cu" "B.Mask" "B.Paste")
			(net "IRQ_UV_DETECT_N")
		)
		(zone
			(layer "B.Cu")
			(hatch none 0.5)
			(connect_pads
				(clearance 0)
			)
			(min_thickness 0.25)
			(keepout
				(tracks not_allowed)
				(vias allowed)
				(pads allowed)
				(copperpour not_allowed)
				(footprints allowed)
			)
			(placement
				(enabled no)
				(sheetname "")
			)
			(fill
				(thermal_gap 0.5)
				(thermal_bridge_width 0.5)
				(island_removal_mode 0)
			)
			(polygon
				(pts
					(xy 15.7734 -86.9061) (xy 15.7734 -87.4141) (xy 16.1544 -87.4141) (xy 16.1544 -86.9061)
				)
			)
		)
		(zone
			(layer "B.Cu")
			(hatch none 0.5)
			(connect_pads
				(clearance 0)
			)
			(min_thickness 0.25)
			(keepout
				(tracks allowed)
				(vias not_allowed)
				(pads allowed)
				(copperpour not_allowed)
				(footprints allowed)
			)
			(placement
				(enabled no)
				(sheetname "")
			)
			(fill
				(thermal_gap 0.5)
				(thermal_bridge_width 0.5)
				(island_removal_mode 0)
			)
			(polygon
				(pts
					(xy 16.1544 -86.9061) (xy 16.1544 -87.4141) (xy 15.7734 -87.4141) (xy 15.7734 -86.9061)
				)
			)
		)
	)
	(footprint ""
		(layer "B.Cu")
		(at 17.83842 -100.60432 90)
		(property "Reference" "C9N12"
			(at 0 0 90)
			(layer "B.SilkS")
			(hide yes)
			(effects
				(font
					(size 1.27 1.27)
				)
				(justify mirror)
			)
		)
		(property "Value" ""
			(at 0 0 90)
			(layer "B.Fab")
			(effects
				(font
					(size 1.27 1.27)
				)
				(justify mirror)
			)
		)
		(duplicate_pad_numbers_are_jumpers no)
		(fp_poly
			(pts
				(xy -0.3048 -0.1016) (xy -0.3048 0.9906) (xy 0.3048 0.9906) (xy 0.3048 -0.1016)
			)
			(stroke
				(width 0)
				(type default)
			)
			(fill no)
			(layer "B.CrtYd")
		)
		(fp_line
			(start 0.3048 -0.1016)
			(end 0.3048 0.9906)
			(stroke
				(width 0.1)
				(type default)
			)
			(layer "B.Fab")
		)
		(fp_line
			(start -0.3048 -0.1016)
			(end 0.3048 -0.1016)
			(stroke
				(width 0.1)
				(type default)
			)
			(layer "B.Fab")
		)
		(fp_line
			(start 0.3048 0.9906)
			(end -0.3048 0.9906)
			(stroke
				(width 0.1)
				(type default)
			)
			(layer "B.Fab")
		)
		(fp_line
			(start -0.3048 0.9906)
			(end -0.3048 -0.1016)
			(stroke
				(width 0.1)
				(type default)
			)
			(layer "B.Fab")
		)
		(pad "1" smd rect
			(at 0 0 270)
			(size 0.508 0.508)
			(layers "B.Cu" "B.Mask" "B.Paste")
			(net "P3E_CPU1_PE3_MP_C_TXP<9>")
		)
		(pad "2" smd rect
			(at 0 0.889 270)
			(size 0.508 0.508)
			(layers "B.Cu" "B.Mask" "B.Paste")
			(net "P3E_CPU1_PE3_MP_TXP<9>")
		)
		(zone
			(layer "B.Cu")
			(hatch none 0.5)
			(connect_pads
				(clearance 0)
			)
			(min_thickness 0.25)
			(keepout
				(tracks allowed)
				(vias not_allowed)
				(pads allowed)
				(copperpour not_allowed)
				(footprints allowed)
			)
			(placement
				(enabled no)
				(sheetname "")
			)
			(fill
				(thermal_gap 0.5)
				(thermal_bridge_width 0.5)
				(island_removal_mode 0)
			)
			(polygon
				(pts
					(xy 18.09242 -100.85832) (xy 18.09242 -100.35032) (xy 18.47342 -100.35032) (xy 18.47342 -100.85832)
				)
			)
		)
		(zone
			(layer "B.Cu")
			(hatch none 0.5)
			(connect_pads
				(clearance 0)
			)
			(min_thickness 0.25)
			(keepout
				(tracks not_allowed)
				(vias allowed)
				(pads allowed)
				(copperpour not_allowed)
				(footprints allowed)
			)
			(placement
				(enabled no)
				(sheetname "")
			)
			(fill
				(thermal_gap 0.5)
				(thermal_bridge_width 0.5)
				(island_removal_mode 0)
			)
			(polygon
				(pts
					(xy 18.47342 -100.85832) (xy 18.47342 -100.35032) (xy 18.09242 -100.35032) (xy 18.09242 -100.85832)
				)
			)
		)
	)
	(footprint ""
		(layer "B.Cu")
		(at 30.554168 -135.3312 90)
		(property "Reference" "C9M1"
			(at 0 0 90)
			(layer "B.SilkS")
			(hide yes)
			(effects
				(font
					(size 1.27 1.27)
				)
				(justify mirror)
			)
		)
		(property "Value" ""
			(at 0 0 90)
			(layer "B.Fab")
			(effects
				(font
					(size 1.27 1.27)
				)
				(justify mirror)
			)
		)
		(duplicate_pad_numbers_are_jumpers no)
		(fp_poly
			(pts
				(xy -0.3048 -0.1016) (xy -0.3048 0.9906) (xy 0.3048 0.9906) (xy 0.3048 -0.1016)
			)
			(stroke
				(width 0)
				(type default)
			)
			(fill no)
			(layer "B.CrtYd")
		)
		(fp_line
			(start 0.3048 -0.1016)
			(end 0.3048 0.9906)
			(stroke
				(width 0.1)
				(type default)
			)
			(layer "B.Fab")
		)
		(fp_line
			(start -0.3048 -0.1016)
			(end 0.3048 -0.1016)
			(stroke
				(width 0.1)
				(type default)
			)
			(layer "B.Fab")
		)
		(fp_line
			(start 0.3048 0.9906)
			(end -0.3048 0.9906)
			(stroke
				(width 0.1)
				(type default)
			)
			(layer "B.Fab")
		)
		(fp_line
			(start -0.3048 0.9906)
			(end -0.3048 -0.1016)
			(stroke
				(width 0.1)
				(type default)
			)
			(layer "B.Fab")
		)
		(pad "1" smd rect
			(at 0 0 270)
			(size 0.508 0.508)
			(layers "B.Cu" "B.Mask" "B.Paste")
			(net "M_K_VREF")
		)
		(pad "2" smd rect
			(at 0 0.889 270)
			(size 0.508 0.508)
			(layers "B.Cu" "B.Mask" "B.Paste")
			(net "GND")
		)
		(zone
			(layer "B.Cu")
			(hatch none 0.5)
			(connect_pads
				(clearance 0)
			)
			(min_thickness 0.25)
			(keepout
				(tracks allowed)
				(vias not_allowed)
				(pads allowed)
				(copperpour not_allowed)
				(footprints allowed)
			)
			(placement
				(enabled no)
				(sheetname "")
			)
			(fill
				(thermal_gap 0.5)
				(thermal_bridge_width 0.5)
				(island_removal_mode 0)
			)
			(polygon
				(pts
					(xy 30.808168 -135.5852) (xy 30.808168 -135.0772) (xy 31.189168 -135.0772) (xy 31.189168 -135.5852)
				)
			)
		)
		(zone
			(layer "B.Cu")
			(hatch none 0.5)
			(connect_pads
				(clearance 0)
			)
			(min_thickness 0.25)
			(keepout
				(tracks not_allowed)
				(vias allowed)
				(pads allowed)
				(copperpour not_allowed)
				(footprints allowed)
			)
			(placement
				(enabled no)
				(sheetname "")
			)
			(fill
				(thermal_gap 0.5)
				(thermal_bridge_width 0.5)
				(island_removal_mode 0)
			)
			(polygon
				(pts
					(xy 31.189168 -135.5852) (xy 31.189168 -135.0772) (xy 30.808168 -135.0772) (xy 30.808168 -135.5852)
				)
			)
		)
	)
)
